FILE_TYPE = CONNECTIVITY;
{Allegro Design Entry HDL 17.4-2019 S026 (4007227) 1/17/2022}
"PAGE_NUMBER" = 112;
0"NC";
1"P2E_MB_BMC_TX_BUF_C_DP<0>";
2"P2E_MB_BMC_TX_BUF_C_DN<0>";
3"P2E_MB_BMC_RX_BUF_DP<0>";
4"P2E_MB_BMC_RX_BUF_DN<0>";
5"P2E_MB_BMC_RX_BUF_C_DP<0>";
6"P2E_MB_BMC_RX_BUF_C_DN<0>";
7"P2E_MB_BMC_RX_BUF2_C_DN<0>";
8"P2E_MB_BMC_RX_BUF2_C_DP<0>";
9"P2E_MB_BMC_TX_BUF2_DN<0>";
10"P2E_MB_BMC_TX_BUF2_DP<0>";
11"P2E_MB_BMC_TX_BUF_DN<0>";
12"P2E_MB_BMC_TX_BUF_DP<0>";
13"P2E_MB_BMC_RX_R1_DN<0>";
14"P2E_MB_BMC_RX_R2_DN<0>";
15"P2E_MB_BMC_RX_R2_DP<0>";
16"P2E_MB_BMC_RX_R1_DP<0>";
17"P2E_MB_BMC_TX_C_R2_DN<0>";
18"P2E_MB_BMC_TX_C_R2_DP<0>";
19"P2E_MB_BMC_TX_C_R1_DN<0>";
20"P2E_MB_BMC_RX_DN<0>";
21"P2E_MB_BMC_RX_DP<0>";
22"P2E_MB_BMC_TX_C_R1_DP<0>";
23"P2E_MB_BMC_TX_C_DN<0>";
24"P2E_MB_BMC_TX_C_DP<0>";
%"Q_RES"
"1","(-7125,4975)","0","pure_quanta","I1";
;
LOCATION"R6154"
$SEC"1"
CDS_SEC"1"
MATERIAL"CHIP"
PACK_TYPE"0201LF"
ROOM"PCIE REDRIVER BOM2"
VALUE"0"
TOLERANCE"5%"
WATTAGE"1/20W"
CDS_LIB"pure_quanta"
PART_NUMBER"CS00001JE10";
"B"
$PN"2"18;
"A"
$PN"1"24;
%"Q_CAP"
"2","(-2550,4275)","0","pure_quanta","I11";
;
LOCATION"C1868"
$SEC"1"
CDS_SEC"1"
PACK_TYPE"0402"
ROOM"PCIE REDRIVER BOM1"
VALUE"0.1UF"
CDS_LIB"pure_quanta"
MATERIAL"X7R"
TOLERANCE"10%"
VOLTAGE"25V"
PART_NUMBER"CH4104K1B00";
"A"
$PN"1"5;
"B"
$PN"2"3;
%"Q_CAP"
"2","(-2550,4225)","0","pure_quanta","I12";
;
LOCATION"C1869"
$SEC"1"
CDS_SEC"1"
ROOM"PCIE REDRIVER BOM1"
VOLTAGE"25V"
VALUE"0.1UF"
MATERIAL"X7R"
PACK_TYPE"0402"
TOLERANCE"10%"
CDS_LIB"pure_quanta"
PART_NUMBER"CH4104K1B00";
"A"
$PN"1"6;
"B"
$PN"2"4;
%"Q_CAP"
"2","(-2700,5250)","0","pure_quanta","I13";
;
LOCATION"C1870"
$SEC"1"
CDS_SEC"1"
ROOM"PCIE REDRIVER BOM1"
CDS_LIB"pure_quanta"
MATERIAL"X7R"
PACK_TYPE"0402"
TOLERANCE"10%"
VALUE"0.1UF"
VOLTAGE"25V"
PART_NUMBER"CH4104K1B00";
"A"
$PN"1"12;
"B"
$PN"2"1;
%"Q_CAP"
"2","(-2700,5200)","0","pure_quanta","I14";
;
LOCATION"C1871"
$SEC"1"
CDS_SEC"1"
VALUE"0.1UF"
TOLERANCE"10%"
VOLTAGE"25V"
MATERIAL"X7R"
PACK_TYPE"0402"
ROOM"PCIE REDRIVER BOM1"
CDS_LIB"pure_quanta"
PART_NUMBER"CH4104K1B00";
"A"
$PN"1"11;
"B"
$PN"2"2;
%"Q_RES"
"1","(-7125,4925)","0","pure_quanta","I2";
;
LOCATION"R6155"
$SEC"1"
CDS_SEC"1"
PACK_TYPE"0201LF"
VALUE"0"
MATERIAL"CHIP"
ROOM"PCIE REDRIVER BOM2"
TOLERANCE"5%"
WATTAGE"1/20W"
CDS_LIB"pure_quanta"
PART_NUMBER"CS00001JE10";
"B"
$PN"2"17;
"A"
$PN"1"23;
%"Q_RES"
"1","(-7225,4200)","0","pure_quanta","I21";
;
LOCATION"R6156"
$SEC"1"
CDS_SEC"1"
ROOM"PCIE REDRIVER BOM1"
MATERIAL"CHIP"
PACK_TYPE"0201LF"
VALUE"0"
TOLERANCE"5%"
WATTAGE"1/20W"
CDS_LIB"pure_quanta"
PART_NUMBER"CS00001JE10";
"B"
$PN"2"16;
"A"
$PN"1"21;
%"Q_RES"
"1","(-7225,4150)","0","pure_quanta","I22";
;
LOCATION"R6157"
$SEC"1"
CDS_SEC"1"
PACK_TYPE"0201LF"
MATERIAL"CHIP"
VALUE"0"
ROOM"PCIE REDRIVER BOM1"
CDS_LIB"pure_quanta"
WATTAGE"1/20W"
TOLERANCE"5%"
PART_NUMBER"CS00001JE10";
"B"
$PN"2"13;
"A"
$PN"1"20;
%"Q_RES"
"1","(-7200,3800)","0","pure_quanta","I23";
;
LOCATION"R6159"
$SEC"1"
CDS_SEC"1"
ROOM"PCIE REDRIVER BOM2"
PACK_TYPE"0201LF"
VALUE"0"
MATERIAL"CHIP"
WATTAGE"1/20W"
TOLERANCE"5%"
CDS_LIB"pure_quanta"
PART_NUMBER"CS00001JE10";
"B"
$PN"2"14;
"A"
$PN"1"20;
%"Q_RES"
"1","(-7200,3850)","0","pure_quanta","I24";
;
LOCATION"R6158"
$SEC"1"
CDS_SEC"1"
MATERIAL"CHIP"
ROOM"PCIE REDRIVER BOM2"
VALUE"0"
PACK_TYPE"0201LF"
WATTAGE"1/20W"
TOLERANCE"5%"
CDS_LIB"pure_quanta"
PART_NUMBER"CS00001JE10";
"B"
$PN"2"15;
"A"
$PN"1"21;
%"Q_RES"
"1","(-7150,5275)","0","pure_quanta","I3";
;
LOCATION"R6153"
$SEC"1"
CDS_SEC"1"
ROOM"PCIE REDRIVER BOM1"
MATERIAL"CHIP"
VALUE"0"
PACK_TYPE"0201LF"
CDS_LIB"pure_quanta"
TOLERANCE"5%"
WATTAGE"1/20W"
PART_NUMBER"CS00001JE10";
"B"
$PN"2"19;
"A"
$PN"1"23;
%"Q_CAP"
"2","(-2650,4850)","0","pure_quanta","I35";
;
LOCATION"C6006"
$SEC"1"
CDS_SEC"1"
VOLTAGE"25V"
VALUE"0.1UF"
ROOM"PCIE REDRIVER BOM2"
TOLERANCE"10%"
PACK_TYPE"0402"
MATERIAL"X7R"
CDS_LIB"pure_quanta"
PART_NUMBER"CH4104K1B00";
"A"
$PN"1"9;
"B"
$PN"2"2;
%"Q_CAP"
"2","(-2650,4900)","0","pure_quanta","I36";
;
LOCATION"C6005"
$SEC"1"
CDS_SEC"1"
ROOM"PCIE REDRIVER BOM2"
VOLTAGE"25V"
VALUE"0.1UF"
TOLERANCE"10%"
PACK_TYPE"0402"
MATERIAL"X7R"
CDS_LIB"pure_quanta"
PART_NUMBER"CH4104K1B00";
"A"
$PN"1"10;
"B"
$PN"2"1;
%"Q_CAP"
"2","(-2550,3925)","0","pure_quanta","I43";
;
LOCATION"C6007"
$SEC"1"
CDS_SEC"1"
ROOM"PCIE REDRIVER BOM2"
CDS_LIB"pure_quanta"
VOLTAGE"25V"
VALUE"0.1UF"
TOLERANCE"10%"
PACK_TYPE"0402"
MATERIAL"X7R"
PART_NUMBER"CH4104K1B00";
"A"
$PN"1"8;
"B"
$PN"2"3;
%"Q_CAP"
"2","(-2550,3875)","0","pure_quanta","I44";
;
LOCATION"C6008"
$SEC"1"
CDS_SEC"1"
ROOM"PCIE REDRIVER BOM2"
VOLTAGE"25V"
VALUE"0.1UF"
CDS_LIB"pure_quanta"
TOLERANCE"10%"
PACK_TYPE"0402"
MATERIAL"X7R"
PART_NUMBER"CH4104K1B00";
"A"
$PN"1"7;
"B"
$PN"2"4;
%"Q_RES"
"1","(-7150,5325)","0","pure_quanta","I8";
;
LOCATION"R6152"
$SEC"1"
CDS_SEC"1"
TOLERANCE"5%"
MATERIAL"CHIP"
WATTAGE"1/20W"
VALUE"0"
PACK_TYPE"0201LF"
ROOM"PCIE REDRIVER BOM1"
CDS_LIB"pure_quanta"
PART_NUMBER"CS00001JE10";
"B"
$PN"2"22;
"A"
$PN"1"24;
END.
